# BASEBOARD_FAB2 (Tioga Pass) — schematic netlist excerpt (pin names and nets, part order shuffled) for the footprints in the layout excerpt that follows; sources: Cadence DE-HDL packaged netlist, KiCad conversion of Wiwynn_Tioga_Pass_MB.brd

C7L3  CAP  10UF 4V 20% X6S  pkg 0603LF  page 234 : A = PVPP_KLM ; B = GND

(kicad_pcb
	(version 20260206)
	(generator "pcbnew")
	(generator_version "10.0")
	(general
		(thickness 1.6)
		(legacy_teardrops no)
	)
	(paper "A4")
	(title_block
		(title "Wiwynn_Tioga_Pass_MB.brd")
		(comment 1 "Tioga Pass / footprints 3282-3282 of 4770")
	)
	(layers
		(0 "F.Cu" signal "TOP")
		(4 "In1.Cu" signal "L2GND")
		(6 "In2.Cu" signal "L3")
		(8 "In3.Cu" signal "L4GND")
		(10 "In4.Cu" signal "L5")
		(12 "In5.Cu" signal "L6GND")
		(14 "In6.Cu" signal "L7VCC")
		(16 "In7.Cu" signal "L8VCC")
		(18 "In8.Cu" signal "L9GND")
		(20 "In9.Cu" signal "L10")
		(22 "In10.Cu" signal "L11GND")
		(24 "In11.Cu" signal "L12")
		(26 "In12.Cu" signal "L13GND")
		(2 "B.Cu" signal "BOTTOM")
		(9 "F.Adhes" user "F.Adhesive")
		(11 "B.Adhes" user "B.Adhesive")
		(13 "F.Paste" user "Package Geometry/Pastemask Top")
		(15 "B.Paste" user "Package Geometry/Pastemask Bottom")
		(5 "F.SilkS" user "Ref Des/Silkscreen Top")
		(7 "B.SilkS" user "Ref Des/Silkscreen Bottom")
		(1 "F.Mask" user "Board Geometry/Soldermask Top")
		(3 "B.Mask" user "Board Geometry/Soldermask Bottom")
		(17 "Dwgs.User" user "User.Drawings")
		(19 "Cmts.User" user "User.Comments")
		(21 "Eco1.User" user "User.Eco1")
		(23 "Eco2.User" user "User.Eco2")
		(25 "Edge.Cuts" user "Board Geometry/Outline")
		(27 "Margin" user)
		(31 "F.CrtYd" user "Package Geometry/Place Bound Top")
		(29 "B.CrtYd" user "Package Geometry/Place Bound Bottom")
		(35 "F.Fab" user "Ref Des/Assembly Top")
		(33 "B.Fab" user "Ref Des/Assembly Bottom")
	)
	(footprint ""
		(layer "B.Cu")
		(at 153.794968 -154.782012 -90)
		(property "Reference" "C7L3"
			(at 0 0 90)
			(layer "B.SilkS")
			(hide yes)
			(effects
				(font
					(size 1.27 1.27)
				)
				(justify mirror)
			)
		)
		(property "Value" ""
			(at 0 0 90)
			(layer "B.Fab")
			(effects
				(font
					(size 1.27 1.27)
				)
				(justify mirror)
			)
		)
		(duplicate_pad_numbers_are_jumpers no)
		(fp_rect
			(start 0.4953 1.6002)
			(end -0.4953 -0.2032)
			(stroke
				(width 0)
				(type default)
			)
			(fill no)
			(layer "B.CrtYd")
		)
		(fp_line
			(start -0.4953 1.6002)
			(end 0.4953 1.6002)
			(stroke
				(width 0.1)
				(type default)
			)
			(layer "B.Fab")
		)
		(fp_line
			(start 0.4953 1.6002)
			(end 0.4953 -0.2032)
			(stroke
				(width 0.1)
				(type default)
			)
			(layer "B.Fab")
		)
		(fp_line
			(start -0.4953 -0.2032)
			(end -0.4953 1.6002)
			(stroke
				(width 0.1)
				(type default)
			)
			(layer "B.Fab")
		)
		(fp_line
			(start 0.4953 -0.2032)
			(end -0.4953 -0.2032)
			(stroke
				(width 0.1)
				(type default)
			)
			(layer "B.Fab")
		)
		(pad "1" smd rect
			(at 0 0 90)
			(size 0.762 0.889)
			(layers "B.Cu" "B.Mask" "B.Paste")
			(net "PVPP_KLM")
		)
		(pad "2" smd rect
			(at 0 1.397 90)
			(size 0.762 0.889)
			(layers "B.Cu" "B.Mask" "B.Paste")
			(net "GND")
		)
		(zone
			(layer "B.Cu")
			(hatch none 0.5)
			(connect_pads
				(clearance 0)
			)
			(min_thickness 0.25)
			(keepout
				(tracks not_allowed)
				(vias allowed)
				(pads allowed)
				(copperpour not_allowed)
				(footprints allowed)
			)
			(placement
				(enabled no)
				(sheetname "")
			)
			(fill
				(thermal_gap 0.5)
				(thermal_bridge_width 0.5)
				(island_removal_mode 0)
			)
			(polygon
				(pts
					(xy 152.842468 -154.401012) (xy 153.350468 -154.401012) (xy 153.350468 -155.163012) (xy 152.842468 -155.163012)
				)
			)
		)
	)
)
